(kicad_pcb
	(version 20260206)
	(generator "pcbnew")
	(generator_version "10.0")
	(general
		(thickness 1.6)
		(legacy_teardrops no)
	)
	(paper "A4")
	(title_block
		(title "m-2 — Lightning_M.2_BRD.brd")
		(comment 1 "Lightning (Wiwynn / Facebook NVMe JBOF) / footprints 60-68 of 157")
	)
	(layers
		(0 "F.Cu" signal "TOP")
		(4 "In1.Cu" signal "L2GND")
		(6 "In2.Cu" signal "L3")
		(8 "In3.Cu" signal "L4GND")
		(10 "In4.Cu" signal "L5GND")
		(12 "In5.Cu" signal "L6")
		(14 "In6.Cu" signal "L7GND")
		(2 "B.Cu" signal "BOTTOM")
		(9 "F.Adhes" user "F.Adhesive")
		(11 "B.Adhes" user "B.Adhesive")
		(13 "F.Paste" user "Package Geometry/Pastemask Top")
		(15 "B.Paste" user "Package Geometry/Pastemask Bottom")
		(5 "F.SilkS" user "Ref Des/Silkscreen Top")
		(7 "B.SilkS" user "Ref Des/Silkscreen Bottom")
		(1 "F.Mask" user "Board Geometry/Soldermask Top")
		(3 "B.Mask" user "Board Geometry/Soldermask Bottom")
		(17 "Dwgs.User" user "User.Drawings")
		(19 "Cmts.User" user "User.Comments")
		(21 "Eco1.User" user "User.Eco1")
		(23 "Eco2.User" user "User.Eco2")
		(25 "Edge.Cuts" user "Board Geometry/Outline")
		(27 "Margin" user)
		(31 "F.CrtYd" user "Package Geometry/Place Bound Top")
		(29 "B.CrtYd" user "Package Geometry/Place Bound Bottom")
		(35 "F.Fab" user "Ref Des/Assembly Top")
		(33 "B.Fab" user "Ref Des/Assembly Bottom")
	)
	(footprint ""
		(layer "F.Cu")
		(at 37.338 -84.582 180)
		(property "Reference" "PC34"
			(at 0 0 180)
			(layer "F.SilkS")
			(hide yes)
			(effects
				(font
					(size 1.27 1.27)
				)
			)
		)
		(property "Value" "SC10U16V5KX-1-GP"
			(at -0.0762 -6.1214 180)
			(unlocked yes)
			(layer "F.Fab")
			(hide yes)
			(effects
				(font
					(size 1.016 1.016)
					(thickness 0.1524)
				)
			)
		)
		(property "Device Type" "C805H54"
			(at -0.0762 -8.1534 180)
			(unlocked yes)
			(layer "F.Fab")
			(hide yes)
			(effects
				(font
					(size 1.016 1.016)
					(thickness 0.1524)
				)
			)
		)
		(duplicate_pad_numbers_are_jumpers no)
		(fp_line
			(start 0.635 0)
			(end -0.635 0)
			(stroke
				(width 0.508)
				(type default)
			)
			(layer "F.SilkS")
		)
		(fp_rect
			(start -0.9652 1.778)
			(end 0.9652 -1.778)
			(stroke
				(width 0)
				(type default)
			)
			(fill no)
			(layer "F.CrtYd")
		)
		(fp_poly
			(pts
				(xy -0.9652 -1.778) (xy 0.9652 -1.778) (xy 0.9652 1.778) (xy -0.9652 1.778)
			)
			(stroke
				(width 0)
				(type default)
			)
			(fill no)
			(layer "F.Fab")
		)
		(pad "1" smd rect
			(at 0 -0.9652 180)
			(size 1.397 1.143)
			(layers "F.Cu" "F.Mask" "F.Paste")
			(net "P3V3_DEV_VIN")
		)
		(pad "2" smd rect
			(at 0 0.9652 180)
			(size 1.397 1.143)
			(layers "F.Cu" "F.Mask" "F.Paste")
			(net "GND")
		)
	)
	(footprint ""
		(layer "F.Cu")
		(at 42.750994 -76.2)
		(property "Reference" "PR29"
			(at 0 0 0)
			(layer "F.SilkS")
			(hide yes)
			(effects
				(font
					(size 1.27 1.27)
				)
			)
		)
		(property "Value" "100KR2F-L1-GP"
			(at 0.064008 -3.993896 0)
			(unlocked yes)
			(layer "F.Fab")
			(hide yes)
			(effects
				(font
					(size 1.016 1.016)
					(thickness 0.1524)
				)
			)
		)
		(property "Device Type" "R402H16"
			(at 0.064008 -5.517896 0)
			(unlocked yes)
			(layer "F.Fab")
			(hide yes)
			(effects
				(font
					(size 1.016 1.016)
					(thickness 0.1524)
				)
			)
		)
		(duplicate_pad_numbers_are_jumpers no)
		(fp_line
			(start -0.508 -0.9398)
			(end -0.508 0.9398)
			(stroke
				(width 0.1524)
				(type default)
			)
			(layer "F.SilkS")
		)
		(fp_line
			(start 0.508 -0.9398)
			(end -0.508 -0.9398)
			(stroke
				(width 0.1524)
				(type default)
			)
			(layer "F.SilkS")
		)
		(fp_rect
			(start -0.508 0.9398)
			(end 0.508 -0.9398)
			(stroke
				(width 0)
				(type default)
			)
			(fill no)
			(layer "F.CrtYd")
		)
		(fp_rect
			(start -0.508 0.9398)
			(end 0.508 -0.9398)
			(stroke
				(width 0)
				(type default)
			)
			(fill no)
			(layer "F.Fab")
		)
		(pad "1" smd custom
			(at 0 -0.4445)
			(size 0.1397 0.1397)
			(layers "F.Cu" "F.Mask" "F.Paste")
			(net "P3V3_DEV_MODE")
			(options
				(clearance outline)
				(anchor circle)
			)
			(primitives
				(gr_poly
					(pts
						(arc
							(start -0.1778 -0.2794)
							(mid -0.249642 -0.249642)
							(end -0.2794 -0.1778)
						)
						(arc
							(start -0.2794 0.1778)
							(mid -0.249642 0.249642)
							(end -0.1778 0.2794)
						)
						(arc
							(start 0.1778 0.2794)
							(mid 0.249642 0.249642)
							(end 0.2794 0.1778)
						)
						(arc
							(start 0.2794 -0.1778)
							(mid 0.249642 -0.249642)
							(end 0.1778 -0.2794)
						)
					)
					(width 0)
					(fill yes)
				)
			)
		)
		(pad "2" smd custom
			(at 0 0.4445)
			(size 0.1397 0.1397)
			(layers "F.Cu" "F.Mask" "F.Paste")
			(net "P3V3_DEV_PWRGD")
			(options
				(clearance outline)
				(anchor circle)
			)
			(primitives
				(gr_poly
					(pts
						(arc
							(start -0.1778 -0.2794)
							(mid -0.249642 -0.249642)
							(end -0.2794 -0.1778)
						)
						(arc
							(start -0.2794 0.1778)
							(mid -0.249642 0.249642)
							(end -0.1778 0.2794)
						)
						(arc
							(start 0.1778 0.2794)
							(mid 0.249642 0.249642)
							(end 0.2794 0.1778)
						)
						(arc
							(start 0.2794 -0.1778)
							(mid 0.249642 -0.249642)
							(end 0.1778 -0.2794)
						)
					)
					(width 0)
					(fill yes)
				)
			)
		)
	)
	(footprint ""
		(layer "F.Cu")
		(at 25.019 -80.518 90)
		(property "Reference" "R31"
			(at 0 0 90)
			(layer "F.SilkS")
			(hide yes)
			(effects
				(font
					(size 1.27 1.27)
				)
			)
		)
		(property "Value" "4K7R2F-GP"
			(at 0.064008 -3.993896 90)
			(unlocked yes)
			(layer "F.Fab")
			(hide yes)
			(effects
				(font
					(size 1.016 1.016)
					(thickness 0.1524)
				)
			)
		)
		(property "Device Type" "R402H16"
			(at 0.064008 -5.517896 90)
			(unlocked yes)
			(layer "F.Fab")
			(hide yes)
			(effects
				(font
					(size 1.016 1.016)
					(thickness 0.1524)
				)
			)
		)
		(duplicate_pad_numbers_are_jumpers no)
		(fp_line
			(start 0.508 -0.9398)
			(end -0.508 -0.9398)
			(stroke
				(width 0.1524)
				(type default)
			)
			(layer "F.SilkS")
		)
		(fp_line
			(start -0.508 -0.9398)
			(end -0.508 0.9398)
			(stroke
				(width 0.1524)
				(type default)
			)
			(layer "F.SilkS")
		)
		(fp_rect
			(start -0.508 0.9398)
			(end 0.508 -0.9398)
			(stroke
				(width 0)
				(type default)
			)
			(fill no)
			(layer "F.CrtYd")
		)
		(fp_rect
			(start -0.508 0.9398)
			(end 0.508 -0.9398)
			(stroke
				(width 0)
				(type default)
			)
			(fill no)
			(layer "F.Fab")
		)
		(pad "1" smd custom
			(at 0 -0.4445 90)
			(size 0.1397 0.1397)
			(layers "F.Cu" "F.Mask" "F.Paste")
			(net "P3V3_DPB")
			(options
				(clearance outline)
				(anchor circle)
			)
			(primitives
				(gr_poly
					(pts
						(arc
							(start -0.1778 -0.2794)
							(mid -0.249642 -0.249642)
							(end -0.2794 -0.1778)
						)
						(arc
							(start -0.2794 0.1778)
							(mid -0.249642 0.249642)
							(end -0.1778 0.2794)
						)
						(arc
							(start 0.1778 0.2794)
							(mid 0.249642 0.249642)
							(end 0.2794 0.1778)
						)
						(arc
							(start 0.2794 -0.1778)
							(mid 0.249642 -0.249642)
							(end 0.1778 -0.2794)
						)
					)
					(width 0)
					(fill yes)
				)
			)
		)
		(pad "2" smd custom
			(at 0 0.4445 90)
			(size 0.1397 0.1397)
			(layers "F.Cu" "F.Mask" "F.Paste")
			(net "Z50_SMB_SWITCH_ADDRESS_A0")
			(options
				(clearance outline)
				(anchor circle)
			)
			(primitives
				(gr_poly
					(pts
						(arc
							(start -0.1778 -0.2794)
							(mid -0.249642 -0.249642)
							(end -0.2794 -0.1778)
						)
						(arc
							(start -0.2794 0.1778)
							(mid -0.249642 0.249642)
							(end -0.1778 0.2794)
						)
						(arc
							(start 0.1778 0.2794)
							(mid 0.249642 0.249642)
							(end 0.2794 0.1778)
						)
						(arc
							(start 0.2794 -0.1778)
							(mid 0.249642 -0.249642)
							(end 0.1778 -0.2794)
						)
					)
					(width 0)
					(fill yes)
				)
			)
		)
	)
	(footprint ""
		(layer "F.Cu")
		(at 73.66 -41.021)
		(property "Reference" "C42"
			(at 0 0 0)
			(layer "F.SilkS")
			(hide yes)
			(effects
				(font
					(size 1.27 1.27)
				)
			)
		)
		(property "Value" "SCD1U16V2KX-3GP"
			(at 1.1811 -2.7051 0)
			(unlocked yes)
			(layer "F.Fab")
			(hide yes)
			(effects
				(font
					(size 1.016 1.016)
					(thickness 0.1524)
				)
			)
		)
		(property "Device Type" "C402H22"
			(at 1.1811 -4.2291 0)
			(unlocked yes)
			(layer "F.Fab")
			(hide yes)
			(effects
				(font
					(size 1.016 1.016)
					(thickness 0.1524)
				)
			)
		)
		(duplicate_pad_numbers_are_jumpers no)
		(fp_rect
			(start -0.4318 0.9525)
			(end 0.4318 -0.9525)
			(stroke
				(width 0)
				(type default)
			)
			(fill no)
			(layer "F.CrtYd")
		)
		(fp_rect
			(start -0.4318 0.9525)
			(end 0.4318 -0.9525)
			(stroke
				(width 0)
				(type default)
			)
			(fill no)
			(layer "F.Fab")
		)
		(pad "1" smd custom
			(at 0 -0.4445)
			(size 0.1524 0.1524)
			(layers "F.Cu" "F.Mask" "F.Paste")
			(net "P3V3_DPB")
			(options
				(clearance outline)
				(anchor circle)
			)
			(primitives
				(gr_poly
					(pts
						(arc
							(start 0.3048 -0.2032)
							(mid 0.275042 -0.275042)
							(end 0.2032 -0.3048)
						)
						(arc
							(start -0.2032 -0.3048)
							(mid -0.275042 -0.275042)
							(end -0.3048 -0.2032)
						)
						(arc
							(start -0.3048 0.2032)
							(mid -0.275042 0.275042)
							(end -0.2032 0.3048)
						)
						(arc
							(start 0.2032 0.3048)
							(mid 0.275042 0.275042)
							(end 0.3048 0.2032)
						)
					)
					(width 0)
					(fill yes)
				)
			)
		)
		(pad "2" smd custom
			(at 0 0.4445)
			(size 0.1524 0.1524)
			(layers "F.Cu" "F.Mask" "F.Paste")
			(net "GND")
			(options
				(clearance outline)
				(anchor circle)
			)
			(primitives
				(gr_poly
					(pts
						(arc
							(start 0.3048 -0.2032)
							(mid 0.275042 -0.275042)
							(end 0.2032 -0.3048)
						)
						(arc
							(start -0.2032 -0.3048)
							(mid -0.275042 -0.275042)
							(end -0.3048 -0.2032)
						)
						(arc
							(start -0.3048 0.2032)
							(mid -0.275042 0.275042)
							(end -0.2032 0.3048)
						)
						(arc
							(start 0.2032 0.3048)
							(mid 0.275042 0.275042)
							(end 0.3048 0.2032)
						)
					)
					(width 0)
					(fill yes)
				)
			)
		)
	)
	(footprint ""
		(layer "F.Cu")
		(at 50.751994 -75.692)
		(property "Reference" "PR39"
			(at 0 0 0)
			(layer "F.SilkS")
			(hide yes)
			(effects
				(font
					(size 1.27 1.27)
				)
			)
		)
		(property "Value" "45K3R2F-L-GP"
			(at 0.064008 -3.993896 0)
			(unlocked yes)
			(layer "F.Fab")
			(hide yes)
			(effects
				(font
					(size 1.016 1.016)
					(thickness 0.1524)
				)
			)
		)
		(property "Device Type" "R402H16"
			(at 0.064008 -5.517896 0)
			(unlocked yes)
			(layer "F.Fab")
			(hide yes)
			(effects
				(font
					(size 1.016 1.016)
					(thickness 0.1524)
				)
			)
		)
		(duplicate_pad_numbers_are_jumpers no)
		(fp_line
			(start -0.508 -0.9398)
			(end -0.508 0.9398)
			(stroke
				(width 0.1524)
				(type default)
			)
			(layer "F.SilkS")
		)
		(fp_line
			(start 0.508 -0.9398)
			(end -0.508 -0.9398)
			(stroke
				(width 0.1524)
				(type default)
			)
			(layer "F.SilkS")
		)
		(fp_rect
			(start -0.508 0.9398)
			(end 0.508 -0.9398)
			(stroke
				(width 0)
				(type default)
			)
			(fill no)
			(layer "F.CrtYd")
		)
		(fp_rect
			(start -0.508 0.9398)
			(end 0.508 -0.9398)
			(stroke
				(width 0)
				(type default)
			)
			(fill no)
			(layer "F.Fab")
		)
		(pad "1" smd custom
			(at 0 -0.4445)
			(size 0.1397 0.1397)
			(layers "F.Cu" "F.Mask" "F.Paste")
			(net "P3V3_DEV_VFB")
			(options
				(clearance outline)
				(anchor circle)
			)
			(primitives
				(gr_poly
					(pts
						(arc
							(start -0.1778 -0.2794)
							(mid -0.249642 -0.249642)
							(end -0.2794 -0.1778)
						)
						(arc
							(start -0.2794 0.1778)
							(mid -0.249642 0.249642)
							(end -0.1778 0.2794)
						)
						(arc
							(start 0.1778 0.2794)
							(mid 0.249642 0.249642)
							(end 0.2794 0.1778)
						)
						(arc
							(start 0.2794 -0.1778)
							(mid 0.249642 -0.249642)
							(end 0.1778 -0.2794)
						)
					)
					(width 0)
					(fill yes)
				)
			)
		)
		(pad "2" smd custom
			(at 0 0.4445)
			(size 0.1397 0.1397)
			(layers "F.Cu" "F.Mask" "F.Paste")
			(net "P3V3_DEV_VFB_R")
			(options
				(clearance outline)
				(anchor circle)
			)
			(primitives
				(gr_poly
					(pts
						(arc
							(start -0.1778 -0.2794)
							(mid -0.249642 -0.249642)
							(end -0.2794 -0.1778)
						)
						(arc
							(start -0.2794 0.1778)
							(mid -0.249642 0.249642)
							(end -0.1778 0.2794)
						)
						(arc
							(start 0.1778 0.2794)
							(mid 0.249642 0.249642)
							(end 0.2794 0.1778)
						)
						(arc
							(start 0.2794 -0.1778)
							(mid 0.249642 -0.249642)
							(end 0.1778 -0.2794)
						)
					)
					(width 0)
					(fill yes)
				)
			)
		)
	)
	(footprint ""
		(layer "F.Cu")
		(at 75.311 -63.246 90)
		(property "Reference" "R2"
			(at 0 0 90)
			(layer "F.SilkS")
			(hide yes)
			(effects
				(font
					(size 1.27 1.27)
				)
			)
		)
		(property "Value" "0R2J-2-GP"
			(at 0.064008 -3.993896 90)
			(unlocked yes)
			(layer "F.Fab")
			(hide yes)
			(effects
				(font
					(size 1.016 1.016)
					(thickness 0.1524)
				)
			)
		)
		(property "Device Type" "R402H16"
			(at 0.064008 -5.517896 90)
			(unlocked yes)
			(layer "F.Fab")
			(hide yes)
			(effects
				(font
					(size 1.016 1.016)
					(thickness 0.1524)
				)
			)
		)
		(duplicate_pad_numbers_are_jumpers no)
		(fp_line
			(start 0.508 -0.9398)
			(end -0.508 -0.9398)
			(stroke
				(width 0.1524)
				(type default)
			)
			(layer "F.SilkS")
		)
		(fp_line
			(start -0.508 -0.9398)
			(end -0.508 0.9398)
			(stroke
				(width 0.1524)
				(type default)
			)
			(layer "F.SilkS")
		)
		(fp_rect
			(start -0.508 0.9398)
			(end 0.508 -0.9398)
			(stroke
				(width 0)
				(type default)
			)
			(fill no)
			(layer "F.CrtYd")
		)
		(fp_rect
			(start -0.508 0.9398)
			(end 0.508 -0.9398)
			(stroke
				(width 0)
				(type default)
			)
			(fill no)
			(layer "F.Fab")
		)
		(pad "1" smd custom
			(at 0 -0.4445 90)
			(size 0.1397 0.1397)
			(layers "F.Cu" "F.Mask" "F.Paste")
			(net "Z50_SSD_A_PRESENT_R#")
			(options
				(clearance outline)
				(anchor circle)
			)
			(primitives
				(gr_poly
					(pts
						(arc
							(start -0.1778 -0.2794)
							(mid -0.249642 -0.249642)
							(end -0.2794 -0.1778)
						)
						(arc
							(start -0.2794 0.1778)
							(mid -0.249642 0.249642)
							(end -0.1778 0.2794)
						)
						(arc
							(start 0.1778 0.2794)
							(mid 0.249642 0.249642)
							(end 0.2794 0.1778)
						)
						(arc
							(start 0.2794 -0.1778)
							(mid 0.249642 -0.249642)
							(end 0.1778 -0.2794)
						)
					)
					(width 0)
					(fill yes)
				)
			)
		)
		(pad "2" smd custom
			(at 0 0.4445 90)
			(size 0.1397 0.1397)
			(layers "F.Cu" "F.Mask" "F.Paste")
			(net "Z50_SSD_A_PRSNT#")
			(options
				(clearance outline)
				(anchor circle)
			)
			(primitives
				(gr_poly
					(pts
						(arc
							(start -0.1778 -0.2794)
							(mid -0.249642 -0.249642)
							(end -0.2794 -0.1778)
						)
						(arc
							(start -0.2794 0.1778)
							(mid -0.249642 0.249642)
							(end -0.1778 0.2794)
						)
						(arc
							(start 0.1778 0.2794)
							(mid 0.249642 0.249642)
							(end 0.2794 0.1778)
						)
						(arc
							(start 0.2794 -0.1778)
							(mid 0.249642 -0.249642)
							(end 0.1778 -0.2794)
						)
					)
					(width 0)
					(fill yes)
				)
			)
		)
	)
	(footprint ""
		(layer "F.Cu")
		(at 75.438 -30.734)
		(property "Reference" "C43"
			(at 0 0 0)
			(layer "F.SilkS")
			(hide yes)
			(effects
				(font
					(size 1.27 1.27)
				)
			)
		)
		(property "Value" "SC1U16V3KX-5GP"
			(at 0 -2.8194 0)
			(unlocked yes)
			(layer "F.Fab")
			(hide yes)
			(effects
				(font
					(size 1.016 1.016)
					(thickness 0.1524)
				)
			)
		)
		(property "Device Type" "C603H36"
			(at 0 -4.3434 0)
			(unlocked yes)
			(layer "F.Fab")
			(hide yes)
			(effects
				(font
					(size 1.016 1.016)
					(thickness 0.1524)
				)
			)
		)
		(duplicate_pad_numbers_are_jumpers no)
		(fp_line
			(start 0.508 0)
			(end -0.508 0)
			(stroke
				(width 0.2032)
				(type default)
			)
			(layer "F.SilkS")
		)
		(fp_rect
			(start -0.5842 1.3335)
			(end 0.5842 -1.3335)
			(stroke
				(width 0)
				(type default)
			)
			(fill no)
			(layer "F.CrtYd")
		)
		(fp_rect
			(start -0.5842 1.3335)
			(end 0.5842 -1.3335)
			(stroke
				(width 0)
				(type default)
			)
			(fill no)
			(layer "F.Fab")
		)
		(pad "1" smd custom
			(at 0 -0.762)
			(size 0.2159 0.2159)
			(layers "F.Cu" "F.Mask" "F.Paste")
			(net "P3V3_DPB")
			(options
				(clearance outline)
				(anchor circle)
			)
			(primitives
				(gr_poly
					(pts
						(arc
							(start -0.3302 -0.4318)
							(mid -0.402042 -0.402042)
							(end -0.4318 -0.3302)
						)
						(arc
							(start -0.4318 0.3302)
							(mid -0.402042 0.402042)
							(end -0.3302 0.4318)
						)
						(arc
							(start 0.3302 0.4318)
							(mid 0.402042 0.402042)
							(end 0.4318 0.3302)
						)
						(arc
							(start 0.4318 -0.3302)
							(mid 0.402042 -0.402042)
							(end 0.3302 -0.4318)
						)
					)
					(width 0)
					(fill yes)
				)
			)
		)
		(pad "2" smd custom
			(at 0 0.762)
			(size 0.2159 0.2159)
			(layers "F.Cu" "F.Mask" "F.Paste")
			(net "GND")
			(options
				(clearance outline)
				(anchor circle)
			)
			(primitives
				(gr_poly
					(pts
						(arc
							(start -0.3302 -0.4318)
							(mid -0.402042 -0.402042)
							(end -0.4318 -0.3302)
						)
						(arc
							(start -0.4318 0.3302)
							(mid -0.402042 0.402042)
							(end -0.3302 0.4318)
						)
						(arc
							(start 0.3302 0.4318)
							(mid 0.402042 0.402042)
							(end 0.4318 0.3302)
						)
						(arc
							(start 0.4318 -0.3302)
							(mid 0.402042 -0.402042)
							(end 0.3302 -0.4318)
						)
					)
					(width 0)
					(fill yes)
				)
			)
		)
	)
	(footprint ""
		(layer "F.Cu")
		(at 73.000108 -87.810086)
		(property "Reference" "H1"
			(at 0 0 0)
			(layer "F.SilkS")
			(hide yes)
			(effects
				(font
					(size 1.27 1.27)
				)
			)
		)
		(property "Value" "HOLE315R140-GP"
			(at 0 -7.5692 0)
			(unlocked yes)
			(layer "F.Fab")
			(hide yes)
			(effects
				(font
					(size 1.016 1.016)
					(thickness 0.1524)
				)
			)
		)
		(property "Device Type" "HOLE315R140"
			(at 0 -9.0932 0)
			(unlocked yes)
			(layer "F.Fab")
			(hide yes)
			(effects
				(font
					(size 1.016 1.016)
					(thickness 0.1524)
				)
			)
		)
		(duplicate_pad_numbers_are_jumpers no)
		(fp_poly
			(pts
				(arc
					(start 4.3053 0)
					(mid -4.3053 0)
					(end 4.3053 0)
				)
			)
			(stroke
				(width 0)
				(type default)
			)
			(fill no)
			(layer "F.CrtYd")
		)
		(fp_poly
			(pts
				(arc
					(start 4.3053 0)
					(mid -4.3053 0)
					(end 4.3053 0)
				)
			)
			(stroke
				(width 0)
				(type default)
			)
			(fill no)
			(layer "F.Fab")
		)
		(pad "1" thru_hole circle
			(at 0.00127 0.00127)
			(size 8.001 8.001)
			(drill 3.556)
			(layers "*.Cu" "*.Mask")
			(remove_unused_layers no)
			(net "GND")
			(clearance -1.7145)
			(thermal_gap 0.3048)
			(padstack
				(mode front_inner_back)
				(layer "Inner"
					(shape circle)
					(size 3.9624 3.9624)
					(clearance 0.3048)
				)
				(layer "B.Cu"
					(shape circle)
					(size 8.001 8.001)
					(clearance -1.7145)
				)
			)
		)
	)
	(footprint ""
		(layer "F.Cu")
		(at 20.447 -74.597006 90)
		(property "Reference" "PC24"
			(at 0 0 90)
			(layer "F.SilkS")
			(hide yes)
			(effects
				(font
					(size 1.27 1.27)
				)
			)
		)
		(property "Value" "SC22U6D3V5MX-5-GP"
			(at -0.0762 -6.1214 90)
			(unlocked yes)
			(layer "F.Fab")
			(hide yes)
			(effects
				(font
					(size 1.016 1.016)
					(thickness 0.1524)
				)
			)
		)
		(property "Device Type" "C805H56"
			(at -0.0762 -8.1534 90)
			(unlocked yes)
			(layer "F.Fab")
			(hide yes)
			(effects
				(font
					(size 1.016 1.016)
					(thickness 0.1524)
				)
			)
		)
		(duplicate_pad_numbers_are_jumpers no)
		(fp_line
			(start 0.635 0)
			(end -0.635 0)
			(stroke
				(width 0.508)
				(type default)
			)
			(layer "F.SilkS")
		)
		(fp_rect
			(start -0.9652 1.778)
			(end 0.9652 -1.778)
			(stroke
				(width 0)
				(type default)
			)
			(fill no)
			(layer "F.CrtYd")
		)
		(fp_poly
			(pts
				(xy -0.9652 -1.778) (xy 0.9652 -1.778) (xy 0.9652 1.778) (xy -0.9652 1.778)
			)
			(stroke
				(width 0)
				(type default)
			)
			(fill no)
			(layer "F.Fab")
		)
		(pad "1" smd rect
			(at 0 -0.9652 90)
			(size 1.397 1.143)
			(layers "F.Cu" "F.Mask" "F.Paste")
			(net "P1V8_PWR")
		)
		(pad "2" smd rect
			(at 0 0.9652 90)
			(size 1.397 1.143)
			(layers "F.Cu" "F.Mask" "F.Paste")
			(net "GND")
		)
	)
)
